FILE_TYPE = MULTI_PHYS_TABLE;

PART '9QXL2001BNHGI8'

{========================================================================================}
:VALUE            | PART_TYPE | MATERIAL | PART_NUMBER    = STANDARD | LIFECYCLE | PART_NUMBER   | JEDEC_TYPE          | DESCRIPTION                         | MANUFTR | MANUF_PN         | RD_CMPLS_LVL | CMPLS_LVL | FROM_PJ    | CLASS | DIP_SMD | DATA                     | EE_CHECK_LIST | FP_ECN | PSL | CREATOR | STATUS | MSD  | ESD_CDM | ESD_HBM | ESD_MM | PIN_LENGTH_SHORT_PIN | PIN_LENGTH_LONG_PIN | CREATEDAY  ;
{========================================================================================}
 '9QXL2001BNHGI8' | 'SMLF'    | 'IC'     | 'AJ020010003'(!) = ''       | ''        | 'AJ020010003' |'GQFN80_TH_0-5_6X6'| 'IC OTHER(80P)9QXL2001BNHGI8(GQFN)' | 'IDT'   | '9QXL2001BNHGI8' | 'EP(V1)'     | ''        | 'F0C-ALEN' | 'IC'  | ''      | 'IDT_9QXL2001BNHGI8.pdf' | ''            | ''     | ''  | ''      | ''     | 'NA' | 'NA'    | 'NA'    | 'NA'   | '0 MILS'             | '0 MILS'            | '20190118'
 '9QXL2001BNHGI8' | 'SMLF'    | 'EMPTY'  | 'AJ020010003'(!) = ''       | ''        | 'AJ020010003' |'GQFN80_TH_0-5_6X6'| 'IC OTHER(80P)9QXL2001BNHGI8(GQFN)' | 'IDT'   | '9QXL2001BNHGI8' | 'EP(V1)'     | ''        | 'F0C-ALEN' | 'IC'  | ''      | 'IDT_9QXL2001BNHGI8.pdf' | ''            | ''     | ''  | ''      | ''     | 'NA' | 'NA'    | 'NA'    | 'NA'   | '0 MILS'             | '0 MILS'            | '20190118'

END_PART

END.

